(kicad_pcb
	(version 20260206)
	(generator "pcbnew")
	(generator_version "10.0")
	(general
		(thickness 1.6)
		(legacy_teardrops no)
	)
	(paper "A4")
	(title_block
		(title "Bryce Canyon_SCC_16316-1_OCP.brd")
		(comment 1 "Bryce Canyon / footprints 784-791 of 1561")
	)
	(layers
		(0 "F.Cu" signal "TOP")
		(4 "In1.Cu" signal "L2GND")
		(6 "In2.Cu" signal "L3")
		(8 "In3.Cu" signal "L4VCC")
		(10 "In4.Cu" signal "L5VCC")
		(12 "In5.Cu" signal "L6")
		(14 "In6.Cu" signal "L7GND")
		(2 "B.Cu" signal "BOTTOM")
		(9 "F.Adhes" user "F.Adhesive")
		(11 "B.Adhes" user "B.Adhesive")
		(13 "F.Paste" user "Package Geometry/Pastemask Top")
		(15 "B.Paste" user "Package Geometry/Pastemask Bottom")
		(5 "F.SilkS" user "Ref Des/Silkscreen Top")
		(7 "B.SilkS" user "Ref Des/Silkscreen Bottom")
		(1 "F.Mask" user "Board Geometry/Soldermask Top")
		(3 "B.Mask" user "Board Geometry/Soldermask Bottom")
		(17 "Dwgs.User" user "User.Drawings")
		(19 "Cmts.User" user "User.Comments")
		(21 "Eco1.User" user "User.Eco1")
		(23 "Eco2.User" user "User.Eco2")
		(25 "Edge.Cuts" user "Board Geometry/Outline")
		(27 "Margin" user)
		(31 "F.CrtYd" user "Package Geometry/Place Bound Top")
		(29 "B.CrtYd" user "Package Geometry/Place Bound Bottom")
		(35 "F.Fab" user "Ref Des/Assembly Top")
		(33 "B.Fab" user "Ref Des/Assembly Bottom")
	)
	(footprint ""
		(layer "B.Cu")
		(at 126.290324 -87.256874 180)
		(property "Reference" "R40"
			(at 0 0 0)
			(layer "B.SilkS")
			(hide yes)
			(effects
				(font
					(size 1.27 1.27)
				)
				(justify mirror)
			)
		)
		(property "Value" "4K7R2F-GP"
			(at -0.064008 -3.993896 180)
			(unlocked yes)
			(layer "B.Fab")
			(hide yes)
			(effects
				(font
					(size 1.016 1.016)
					(thickness 0.1524)
				)
				(justify mirror)
			)
		)
		(property "Device Type" "R402H16"
			(at -0.064008 -5.517896 180)
			(unlocked yes)
			(layer "B.Fab")
			(hide yes)
			(effects
				(font
					(size 1.016 1.016)
					(thickness 0.1524)
				)
				(justify mirror)
			)
		)
		(duplicate_pad_numbers_are_jumpers no)
		(fp_line
			(start 0.508 -0.9398)
			(end 0.508 0.9398)
			(stroke
				(width 0.1524)
				(type default)
			)
			(layer "B.SilkS")
		)
		(fp_line
			(start -0.508 -0.9398)
			(end 0.508 -0.9398)
			(stroke
				(width 0.1524)
				(type default)
			)
			(layer "B.SilkS")
		)
		(fp_rect
			(start 0.508 0.9398)
			(end -0.508 -0.9398)
			(stroke
				(width 0)
				(type default)
			)
			(fill no)
			(layer "B.CrtYd")
		)
		(fp_rect
			(start 0.508 0.9398)
			(end -0.508 -0.9398)
			(stroke
				(width 0)
				(type default)
			)
			(fill no)
			(layer "B.Fab")
		)
		(pad "1" smd custom
			(at 0 -0.4445)
			(size 0.1397 0.1397)
			(layers "B.Cu" "B.Mask" "B.Paste")
			(net "EXP_SIO_CLK_IN")
			(options
				(clearance outline)
				(anchor circle)
			)
			(primitives
				(gr_poly
					(pts
						(arc
							(start -0.1778 0.2794)
							(mid -0.249642 0.249642)
							(end -0.2794 0.1778)
						)
						(arc
							(start -0.2794 -0.1778)
							(mid -0.249642 -0.249642)
							(end -0.1778 -0.2794)
						)
						(arc
							(start 0.1778 -0.2794)
							(mid 0.249642 -0.249642)
							(end 0.2794 -0.1778)
						)
						(arc
							(start 0.2794 0.1778)
							(mid 0.249642 0.249642)
							(end 0.1778 0.2794)
						)
					)
					(width 0)
					(fill yes)
				)
			)
		)
		(pad "2" smd custom
			(at 0 0.4445)
			(size 0.1397 0.1397)
			(layers "B.Cu" "B.Mask" "B.Paste")
			(net "P1V8_E")
			(options
				(clearance outline)
				(anchor circle)
			)
			(primitives
				(gr_poly
					(pts
						(arc
							(start -0.1778 0.2794)
							(mid -0.249642 0.249642)
							(end -0.2794 0.1778)
						)
						(arc
							(start -0.2794 -0.1778)
							(mid -0.249642 -0.249642)
							(end -0.1778 -0.2794)
						)
						(arc
							(start 0.1778 -0.2794)
							(mid 0.249642 -0.249642)
							(end 0.2794 -0.1778)
						)
						(arc
							(start 0.2794 0.1778)
							(mid 0.249642 0.249642)
							(end 0.1778 0.2794)
						)
					)
					(width 0)
					(fill yes)
				)
			)
		)
	)
	(footprint ""
		(layer "B.Cu")
		(at 192.024 -40.8432 -90)
		(property "Reference" "R182"
			(at 0 0 90)
			(layer "B.SilkS")
			(hide yes)
			(effects
				(font
					(size 1.27 1.27)
				)
				(justify mirror)
			)
		)
		(property "Value" "2K2R2F-GP"
			(at -0.064008 -3.993896 270)
			(unlocked yes)
			(layer "B.Fab")
			(hide yes)
			(effects
				(font
					(size 1.016 1.016)
					(thickness 0.1524)
				)
				(justify mirror)
			)
		)
		(property "Device Type" "R402H16"
			(at -0.064008 -5.517896 270)
			(unlocked yes)
			(layer "B.Fab")
			(hide yes)
			(effects
				(font
					(size 1.016 1.016)
					(thickness 0.1524)
				)
				(justify mirror)
			)
		)
		(duplicate_pad_numbers_are_jumpers no)
		(fp_line
			(start -0.508 -0.9398)
			(end 0.508 -0.9398)
			(stroke
				(width 0.1524)
				(type default)
			)
			(layer "B.SilkS")
		)
		(fp_line
			(start 0.508 -0.9398)
			(end 0.508 0.9398)
			(stroke
				(width 0.1524)
				(type default)
			)
			(layer "B.SilkS")
		)
		(fp_rect
			(start 0.508 0.9398)
			(end -0.508 -0.9398)
			(stroke
				(width 0)
				(type default)
			)
			(fill no)
			(layer "B.CrtYd")
		)
		(fp_rect
			(start 0.508 0.9398)
			(end -0.508 -0.9398)
			(stroke
				(width 0)
				(type default)
			)
			(fill no)
			(layer "B.Fab")
		)
		(pad "1" smd custom
			(at 0 -0.4445 90)
			(size 0.1397 0.1397)
			(layers "B.Cu" "B.Mask" "B.Paste")
			(net "P1V8_C")
			(options
				(clearance outline)
				(anchor circle)
			)
			(primitives
				(gr_poly
					(pts
						(arc
							(start -0.1778 0.2794)
							(mid -0.249642 0.249642)
							(end -0.2794 0.1778)
						)
						(arc
							(start -0.2794 -0.1778)
							(mid -0.249642 -0.249642)
							(end -0.1778 -0.2794)
						)
						(arc
							(start 0.1778 -0.2794)
							(mid 0.249642 -0.249642)
							(end 0.2794 -0.1778)
						)
						(arc
							(start 0.2794 0.1778)
							(mid 0.249642 0.249642)
							(end 0.1778 0.2794)
						)
					)
					(width 0)
					(fill yes)
				)
			)
		)
		(pad "2" smd custom
			(at 0 0.4445 90)
			(size 0.1397 0.1397)
			(layers "B.Cu" "B.Mask" "B.Paste")
			(net "I2C_IOC_0_SDA")
			(options
				(clearance outline)
				(anchor circle)
			)
			(primitives
				(gr_poly
					(pts
						(arc
							(start -0.1778 0.2794)
							(mid -0.249642 0.249642)
							(end -0.2794 0.1778)
						)
						(arc
							(start -0.2794 -0.1778)
							(mid -0.249642 -0.249642)
							(end -0.1778 -0.2794)
						)
						(arc
							(start 0.1778 -0.2794)
							(mid 0.249642 -0.249642)
							(end 0.2794 -0.1778)
						)
						(arc
							(start 0.2794 0.1778)
							(mid 0.249642 0.249642)
							(end 0.1778 0.2794)
						)
					)
					(width 0)
					(fill yes)
				)
			)
		)
	)
	(footprint ""
		(layer "B.Cu")
		(at 124.4981 -60.5028 90)
		(property "Reference" "C252"
			(at 0 0 90)
			(layer "B.SilkS")
			(hide yes)
			(effects
				(font
					(size 1.27 1.27)
				)
				(justify mirror)
			)
		)
		(property "Value" "SCD1U6D3V1KX-GP"
			(at 2.8321 -1.7399 90)
			(unlocked yes)
			(layer "B.Fab")
			(hide yes)
			(effects
				(font
					(size 1.016 1.016)
					(thickness 0.1524)
				)
				(justify mirror)
			)
		)
		(property "Device Type" "C0201H13"
			(at 2.8321 -3.2639 90)
			(unlocked yes)
			(layer "B.Fab")
			(hide yes)
			(effects
				(font
					(size 1.016 1.016)
					(thickness 0.1524)
				)
				(justify mirror)
			)
		)
		(duplicate_pad_numbers_are_jumpers no)
		(fp_rect
			(start 0.2794 0.6477)
			(end -0.2794 -0.6477)
			(stroke
				(width 0)
				(type default)
			)
			(fill no)
			(layer "B.CrtYd")
		)
		(fp_rect
			(start 0.2794 0.6477)
			(end -0.2794 -0.6477)
			(stroke
				(width 0)
				(type default)
			)
			(fill no)
			(layer "B.Fab")
		)
		(pad "1" smd custom
			(at 0 -0.2794 270)
			(size 0.0762 0.0762)
			(layers "B.Cu" "B.Mask" "B.Paste")
			(net "GB_VDDA")
			(options
				(clearance outline)
				(anchor circle)
			)
			(primitives
				(gr_poly
					(pts
						(arc
							(start 0.1524 0.127)
							(mid 0.137521 0.162921)
							(end 0.1016 0.1778)
						)
						(arc
							(start -0.1016 0.1778)
							(mid -0.137521 0.162921)
							(end -0.1524 0.127)
						)
						(arc
							(start -0.1524 -0.127)
							(mid -0.137521 -0.162921)
							(end -0.1016 -0.1778)
						)
						(arc
							(start 0.1016 -0.1778)
							(mid 0.137521 -0.162921)
							(end 0.1524 -0.127)
						)
					)
					(width 0)
					(fill yes)
				)
			)
		)
		(pad "2" smd custom
			(at 0 0.2794 270)
			(size 0.0762 0.0762)
			(layers "B.Cu" "B.Mask" "B.Paste")
			(net "GND")
			(options
				(clearance outline)
				(anchor circle)
			)
			(primitives
				(gr_poly
					(pts
						(arc
							(start 0.1524 0.127)
							(mid 0.137521 0.162921)
							(end 0.1016 0.1778)
						)
						(arc
							(start -0.1016 0.1778)
							(mid -0.137521 0.162921)
							(end -0.1524 0.127)
						)
						(arc
							(start -0.1524 -0.127)
							(mid -0.137521 -0.162921)
							(end -0.1016 -0.1778)
						)
						(arc
							(start 0.1016 -0.1778)
							(mid 0.137521 -0.162921)
							(end 0.1524 -0.127)
						)
					)
					(width 0)
					(fill yes)
				)
			)
		)
	)
	(footprint ""
		(layer "B.Cu")
		(at 186.276488 -33.07969 90)
		(property "Reference" "TP86"
			(at 0 0 90)
			(layer "B.SilkS")
			(hide yes)
			(effects
				(font
					(size 1.27 1.27)
				)
				(justify mirror)
			)
		)
		(property "Value" "TPAD28-2-GP"
			(at 0.0127 -1.6637 90)
			(unlocked yes)
			(layer "B.Fab")
			(hide yes)
			(effects
				(font
					(size 1.016 1.016)
					(thickness 0.1524)
				)
				(justify mirror)
			)
		)
		(property "Device Type" "TPAD28"
			(at 0.0127 -3.1877 90)
			(unlocked yes)
			(layer "B.Fab")
			(hide yes)
			(effects
				(font
					(size 1.016 1.016)
					(thickness 0.1524)
				)
				(justify mirror)
			)
		)
		(duplicate_pad_numbers_are_jumpers no)
		(fp_poly
			(pts
				(arc
					(start 0 0.3556)
					(mid 0 -0.3556)
					(end 0 0.3556)
				)
			)
			(stroke
				(width 0)
				(type default)
			)
			(fill no)
			(layer "B.CrtYd")
		)
		(fp_poly
			(pts
				(arc
					(start 0 0.6096)
					(mid 0 -0.6096)
					(end 0 0.6096)
				)
			)
			(stroke
				(width 0)
				(type default)
			)
			(fill no)
			(layer "B.Fab")
		)
		(pad "1" smd circle
			(at 0 0 270)
			(size 0.7112 0.7112)
			(layers "B.Cu" "B.Mask" "B.Paste")
			(net "IOC_GPIO_29")
		)
	)
	(footprint ""
		(layer "B.Cu")
		(at 90.974926 -67.835272)
		(property "Reference" "R153"
			(at 0 0 0)
			(layer "B.SilkS")
			(hide yes)
			(effects
				(font
					(size 1.27 1.27)
				)
				(justify mirror)
			)
		)
		(property "Value" "10R2F-L-GP"
			(at -0.064008 -3.993896 0)
			(unlocked yes)
			(layer "B.Fab")
			(hide yes)
			(effects
				(font
					(size 1.016 1.016)
					(thickness 0.1524)
				)
				(justify mirror)
			)
		)
		(property "Device Type" "R402H14"
			(at -0.064008 -5.517896 0)
			(unlocked yes)
			(layer "B.Fab")
			(hide yes)
			(effects
				(font
					(size 1.016 1.016)
					(thickness 0.1524)
				)
				(justify mirror)
			)
		)
		(duplicate_pad_numbers_are_jumpers no)
		(fp_line
			(start -0.508 -0.9398)
			(end 0.508 -0.9398)
			(stroke
				(width 0.1524)
				(type default)
			)
			(layer "B.SilkS")
		)
		(fp_line
			(start 0.508 -0.9398)
			(end 0.508 0.9398)
			(stroke
				(width 0.1524)
				(type default)
			)
			(layer "B.SilkS")
		)
		(fp_rect
			(start 0.508 0.9398)
			(end -0.508 -0.9398)
			(stroke
				(width 0)
				(type default)
			)
			(fill no)
			(layer "B.CrtYd")
		)
		(fp_rect
			(start 0.508 0.9398)
			(end -0.508 -0.9398)
			(stroke
				(width 0)
				(type default)
			)
			(fill no)
			(layer "B.Fab")
		)
		(pad "1" smd custom
			(at 0 -0.4445 180)
			(size 0.1397 0.1397)
			(layers "B.Cu" "B.Mask" "B.Paste")
			(net "P1V8_E")
			(options
				(clearance outline)
				(anchor circle)
			)
			(primitives
				(gr_poly
					(pts
						(arc
							(start -0.1778 0.2794)
							(mid -0.249642 0.249642)
							(end -0.2794 0.1778)
						)
						(arc
							(start -0.2794 -0.1778)
							(mid -0.249642 -0.249642)
							(end -0.1778 -0.2794)
						)
						(arc
							(start 0.1778 -0.2794)
							(mid 0.249642 -0.249642)
							(end 0.2794 -0.1778)
						)
						(arc
							(start 0.2794 0.1778)
							(mid 0.249642 0.249642)
							(end 0.1778 0.2794)
						)
					)
					(width 0)
					(fill yes)
				)
			)
		)
		(pad "2" smd custom
			(at 0 0.4445 180)
			(size 0.1397 0.1397)
			(layers "B.Cu" "B.Mask" "B.Paste")
			(net "PLLDDR_VDDA18")
			(options
				(clearance outline)
				(anchor circle)
			)
			(primitives
				(gr_poly
					(pts
						(arc
							(start -0.1778 0.2794)
							(mid -0.249642 0.249642)
							(end -0.2794 0.1778)
						)
						(arc
							(start -0.2794 -0.1778)
							(mid -0.249642 -0.249642)
							(end -0.1778 -0.2794)
						)
						(arc
							(start 0.1778 -0.2794)
							(mid 0.249642 -0.249642)
							(end 0.2794 -0.1778)
						)
						(arc
							(start 0.2794 0.1778)
							(mid 0.249642 0.249642)
							(end 0.1778 0.2794)
						)
					)
					(width 0)
					(fill yes)
				)
			)
		)
	)
	(footprint ""
		(layer "B.Cu")
		(at 107.061 -87.0712 180)
		(property "Reference" "R47"
			(at 0 0 0)
			(layer "B.SilkS")
			(hide yes)
			(effects
				(font
					(size 1.27 1.27)
				)
				(justify mirror)
			)
		)
		(property "Value" "4K75R2F-1-GP"
			(at -0.064008 -3.993896 180)
			(unlocked yes)
			(layer "B.Fab")
			(hide yes)
			(effects
				(font
					(size 1.016 1.016)
					(thickness 0.1524)
				)
				(justify mirror)
			)
		)
		(property "Device Type" "R402H16"
			(at -0.064008 -5.517896 180)
			(unlocked yes)
			(layer "B.Fab")
			(hide yes)
			(effects
				(font
					(size 1.016 1.016)
					(thickness 0.1524)
				)
				(justify mirror)
			)
		)
		(duplicate_pad_numbers_are_jumpers no)
		(fp_line
			(start 0.508 -0.9398)
			(end 0.508 0.9398)
			(stroke
				(width 0.1524)
				(type default)
			)
			(layer "B.SilkS")
		)
		(fp_line
			(start -0.508 -0.9398)
			(end 0.508 -0.9398)
			(stroke
				(width 0.1524)
				(type default)
			)
			(layer "B.SilkS")
		)
		(fp_rect
			(start 0.508 0.9398)
			(end -0.508 -0.9398)
			(stroke
				(width 0)
				(type default)
			)
			(fill no)
			(layer "B.CrtYd")
		)
		(fp_rect
			(start 0.508 0.9398)
			(end -0.508 -0.9398)
			(stroke
				(width 0)
				(type default)
			)
			(fill no)
			(layer "B.Fab")
		)
		(pad "1" smd custom
			(at 0 -0.4445)
			(size 0.1397 0.1397)
			(layers "B.Cu" "B.Mask" "B.Paste")
			(net "GND")
			(options
				(clearance outline)
				(anchor circle)
			)
			(primitives
				(gr_poly
					(pts
						(arc
							(start -0.1778 0.2794)
							(mid -0.249642 0.249642)
							(end -0.2794 0.1778)
						)
						(arc
							(start -0.2794 -0.1778)
							(mid -0.249642 -0.249642)
							(end -0.1778 -0.2794)
						)
						(arc
							(start 0.1778 -0.2794)
							(mid 0.249642 -0.249642)
							(end 0.2794 -0.1778)
						)
						(arc
							(start 0.2794 0.1778)
							(mid 0.249642 0.249642)
							(end 0.1778 0.2794)
						)
					)
					(width 0)
					(fill yes)
				)
			)
		)
		(pad "2" smd custom
			(at 0 0.4445)
			(size 0.1397 0.1397)
			(layers "B.Cu" "B.Mask" "B.Paste")
			(net "EXP_BLINK_IN")
			(options
				(clearance outline)
				(anchor circle)
			)
			(primitives
				(gr_poly
					(pts
						(arc
							(start -0.1778 0.2794)
							(mid -0.249642 0.249642)
							(end -0.2794 0.1778)
						)
						(arc
							(start -0.2794 -0.1778)
							(mid -0.249642 -0.249642)
							(end -0.1778 -0.2794)
						)
						(arc
							(start 0.1778 -0.2794)
							(mid 0.249642 -0.249642)
							(end 0.2794 -0.1778)
						)
						(arc
							(start 0.2794 0.1778)
							(mid 0.249642 0.249642)
							(end 0.1778 0.2794)
						)
					)
					(width 0)
					(fill yes)
				)
			)
		)
	)
	(footprint ""
		(layer "B.Cu")
		(at 189.427612 -45.263816 -90)
		(property "Reference" "TP105"
			(at 0 0 90)
			(layer "B.SilkS")
			(hide yes)
			(effects
				(font
					(size 1.27 1.27)
				)
				(justify mirror)
			)
		)
		(property "Value" "TPAD28-2-GP"
			(at 0.0127 -1.6637 270)
			(unlocked yes)
			(layer "B.Fab")
			(hide yes)
			(effects
				(font
					(size 1.016 1.016)
					(thickness 0.1524)
				)
				(justify mirror)
			)
		)
		(property "Device Type" "TPAD28"
			(at 0.0127 -3.1877 270)
			(unlocked yes)
			(layer "B.Fab")
			(hide yes)
			(effects
				(font
					(size 1.016 1.016)
					(thickness 0.1524)
				)
				(justify mirror)
			)
		)
		(duplicate_pad_numbers_are_jumpers no)
		(fp_poly
			(pts
				(arc
					(start 0 -0.3556)
					(mid 0 0.3556)
					(end 0 -0.3556)
				)
			)
			(stroke
				(width 0)
				(type default)
			)
			(fill no)
			(layer "B.CrtYd")
		)
		(fp_poly
			(pts
				(arc
					(start 0 -0.6096)
					(mid 0 0.6096)
					(end 0 -0.6096)
				)
			)
			(stroke
				(width 0)
				(type default)
			)
			(fill no)
			(layer "B.Fab")
		)
		(pad "1" smd circle
			(at 0 0 90)
			(size 0.7112 0.7112)
			(layers "B.Cu" "B.Mask" "B.Paste")
			(net "XM_ADDR_18")
		)
	)
	(footprint ""
		(layer "B.Cu")
		(at 177.429414 -51.025806 180)
		(property "Reference" "R220"
			(at 0 0 0)
			(layer "B.SilkS")
			(hide yes)
			(effects
				(font
					(size 1.27 1.27)
				)
				(justify mirror)
			)
		)
		(property "Value" "10KR2F-2-GP"
			(at -0.064008 -3.993896 180)
			(unlocked yes)
			(layer "B.Fab")
			(hide yes)
			(effects
				(font
					(size 1.016 1.016)
					(thickness 0.1524)
				)
				(justify mirror)
			)
		)
		(property "Device Type" "R402H16"
			(at -0.064008 -5.517896 180)
			(unlocked yes)
			(layer "B.Fab")
			(hide yes)
			(effects
				(font
					(size 1.016 1.016)
					(thickness 0.1524)
				)
				(justify mirror)
			)
		)
		(duplicate_pad_numbers_are_jumpers no)
		(fp_line
			(start 0.508 -0.9398)
			(end 0.508 0.9398)
			(stroke
				(width 0.1524)
				(type default)
			)
			(layer "B.SilkS")
		)
		(fp_line
			(start -0.508 -0.9398)
			(end 0.508 -0.9398)
			(stroke
				(width 0.1524)
				(type default)
			)
			(layer "B.SilkS")
		)
		(fp_rect
			(start 0.508 0.9398)
			(end -0.508 -0.9398)
			(stroke
				(width 0)
				(type default)
			)
			(fill no)
			(layer "B.CrtYd")
		)
		(fp_rect
			(start 0.508 0.9398)
			(end -0.508 -0.9398)
			(stroke
				(width 0)
				(type default)
			)
			(fill no)
			(layer "B.Fab")
		)
		(pad "1" smd custom
			(at 0 -0.4445)
			(size 0.1397 0.1397)
			(layers "B.Cu" "B.Mask" "B.Paste")
			(net "P1V8_C")
			(options
				(clearance outline)
				(anchor circle)
			)
			(primitives
				(gr_poly
					(pts
						(arc
							(start -0.1778 0.2794)
							(mid -0.249642 0.249642)
							(end -0.2794 0.1778)
						)
						(arc
							(start -0.2794 -0.1778)
							(mid -0.249642 -0.249642)
							(end -0.1778 -0.2794)
						)
						(arc
							(start 0.1778 -0.2794)
							(mid 0.249642 -0.249642)
							(end 0.2794 -0.1778)
						)
						(arc
							(start 0.2794 0.1778)
							(mid 0.249642 0.249642)
							(end 0.1778 0.2794)
						)
					)
					(width 0)
					(fill yes)
				)
			)
		)
		(pad "2" smd custom
			(at 0 0.4445)
			(size 0.1397 0.1397)
			(layers "B.Cu" "B.Mask" "B.Paste")
			(net "XM_NAND_CS_N")
			(options
				(clearance outline)
				(anchor circle)
			)
			(primitives
				(gr_poly
					(pts
						(arc
							(start -0.1778 0.2794)
							(mid -0.249642 0.249642)
							(end -0.2794 0.1778)
						)
						(arc
							(start -0.2794 -0.1778)
							(mid -0.249642 -0.249642)
							(end -0.1778 -0.2794)
						)
						(arc
							(start 0.1778 -0.2794)
							(mid 0.249642 -0.249642)
							(end 0.2794 -0.1778)
						)
						(arc
							(start 0.2794 0.1778)
							(mid 0.249642 0.249642)
							(end 0.1778 0.2794)
						)
					)
					(width 0)
					(fill yes)
				)
			)
		)
	)
)
